(kicad_pcb
	(version 20260206)
	(generator "pcbnew")
	(generator_version "10.0")
	(general
		(thickness 1.6)
		(legacy_teardrops no)
	)
	(paper "A4")
	(title_block
		(title "12092022_DA0F0TFB6D0_F0T_FAN_BOARD_MP5048_D_brd_v02_OCP.brd")
		(comment 1 "Grand Teton / footprints 856-858 of 924")
	)
	(layers
		(0 "F.Cu" signal "TOP")
		(4 "In1.Cu" signal "GND")
		(6 "In2.Cu" signal "IN1")
		(8 "In3.Cu" signal "IN2")
		(10 "In4.Cu" signal "GND1")
		(2 "B.Cu" signal "BOTTOM")
		(9 "F.Adhes" user "F.Adhesive")
		(11 "B.Adhes" user "B.Adhesive")
		(13 "F.Paste" user "Package Geometry/Pastemask Top")
		(15 "B.Paste" user "Package Geometry/Pastemask Bottom")
		(5 "F.SilkS" user "Ref Des/Silkscreen Top")
		(7 "B.SilkS" user "Ref Des/Silkscreen Bottom")
		(1 "F.Mask" user "Board Geometry/Soldermask Top")
		(3 "B.Mask" user "Board Geometry/Soldermask Bottom")
		(17 "Dwgs.User" user "User.Drawings")
		(19 "Cmts.User" user "User.Comments")
		(21 "Eco1.User" user "User.Eco1")
		(23 "Eco2.User" user "User.Eco2")
		(25 "Edge.Cuts" user "Board Geometry/Outline")
		(27 "Margin" user)
		(31 "F.CrtYd" user "Package Geometry/Place Bound Top")
		(29 "B.CrtYd" user "Package Geometry/Place Bound Bottom")
		(35 "F.Fab" user "Ref Des/Assembly Top")
		(33 "B.Fab" user "Ref Des/Assembly Bottom")
	)
	(footprint ""
		(layer "B.Cu")
		(at 46.482 -73.971912 -90)
		(property "Reference" "PR42"
			(at 0 0 90)
			(layer "B.SilkS")
			(hide yes)
			(effects
				(font
					(size 1.27 1.27)
				)
				(justify mirror)
			)
		)
		(property "Value" ""
			(at 0 0 90)
			(layer "B.Fab")
			(effects
				(font
					(size 1.27 1.27)
				)
				(justify mirror)
			)
		)
		(duplicate_pad_numbers_are_jumpers no)
		(fp_line
			(start -0.7874 0.4064)
			(end 0.7874 0.4064)
			(stroke
				(width 0.1524)
				(type default)
			)
			(layer "B.SilkS")
		)
		(fp_line
			(start 0.7874 0.4064)
			(end 0.7874 -0.4064)
			(stroke
				(width 0.1524)
				(type default)
			)
			(layer "B.SilkS")
		)
		(fp_line
			(start -0.7874 -0.4064)
			(end -0.7874 0.4064)
			(stroke
				(width 0.1524)
				(type default)
			)
			(layer "B.SilkS")
		)
		(fp_line
			(start 0.7874 -0.4064)
			(end -0.7874 -0.4064)
			(stroke
				(width 0.1524)
				(type default)
			)
			(layer "B.SilkS")
		)
		(fp_line
			(start -0.67945 0.3048)
			(end -0.120396 0.3048)
			(stroke
				(width 0.1)
				(type default)
			)
			(layer "B.Fab")
		)
		(fp_line
			(start -0.120396 0.3048)
			(end -0.120396 0.2794)
			(stroke
				(width 0.1)
				(type default)
			)
			(layer "B.Fab")
		)
		(fp_line
			(start 0.12065 0.3048)
			(end 0.67945 0.3048)
			(stroke
				(width 0.1)
				(type default)
			)
			(layer "B.Fab")
		)
		(fp_line
			(start 0.67945 0.3048)
			(end 0.67945 -0.305054)
			(stroke
				(width 0.1)
				(type default)
			)
			(layer "B.Fab")
		)
		(fp_line
			(start -0.120396 0.2794)
			(end 0.12065 0.2794)
			(stroke
				(width 0.1)
				(type default)
			)
			(layer "B.Fab")
		)
		(fp_line
			(start 0.12065 0.2794)
			(end 0.12065 0.3048)
			(stroke
				(width 0.1)
				(type default)
			)
			(layer "B.Fab")
		)
		(fp_line
			(start -0.12065 -0.2794)
			(end -0.12065 -0.3048)
			(stroke
				(width 0.1)
				(type default)
			)
			(layer "B.Fab")
		)
		(fp_line
			(start 0.12065 -0.2794)
			(end -0.12065 -0.2794)
			(stroke
				(width 0.1)
				(type default)
			)
			(layer "B.Fab")
		)
		(fp_line
			(start -0.67945 -0.3048)
			(end -0.67945 0.3048)
			(stroke
				(width 0.1)
				(type default)
			)
			(layer "B.Fab")
		)
		(fp_line
			(start -0.12065 -0.3048)
			(end -0.67945 -0.3048)
			(stroke
				(width 0.1)
				(type default)
			)
			(layer "B.Fab")
		)
		(fp_line
			(start 0.12065 -0.305054)
			(end 0.12065 -0.2794)
			(stroke
				(width 0.1)
				(type default)
			)
			(layer "B.Fab")
		)
		(fp_line
			(start 0.67945 -0.305054)
			(end 0.12065 -0.305054)
			(stroke
				(width 0.1)
				(type default)
			)
			(layer "B.Fab")
		)
		(pad "1" smd circle
			(at 0.40005 0 90)
			(size 0 0)
			(layers "B.Cu" "B.Mask" "B.Paste")
			(net "GND")
		)
		(pad "2" smd circle
			(at -0.40005 0 90)
			(size 0 0)
			(layers "B.Cu" "B.Mask" "B.Paste")
			(net "FAN_2_IMON")
		)
	)
	(footprint ""
		(layer "B.Cu")
		(at 37.465 -64.837056 90)
		(property "Reference" "PC3121"
			(at 0 0 90)
			(layer "B.SilkS")
			(hide yes)
			(effects
				(font
					(size 1.27 1.27)
				)
				(justify mirror)
			)
		)
		(property "Value" ""
			(at 0 0 90)
			(layer "B.Fab")
			(effects
				(font
					(size 1.27 1.27)
				)
				(justify mirror)
			)
		)
		(duplicate_pad_numbers_are_jumpers no)
		(fp_line
			(start 0.7874 -0.4064)
			(end -0.7874 -0.4064)
			(stroke
				(width 0.1524)
				(type default)
			)
			(layer "B.SilkS")
		)
		(fp_line
			(start -0.7874 -0.4064)
			(end -0.7874 0.4064)
			(stroke
				(width 0.1524)
				(type default)
			)
			(layer "B.SilkS")
		)
		(fp_line
			(start 0.7874 0.4064)
			(end 0.7874 -0.4064)
			(stroke
				(width 0.1524)
				(type default)
			)
			(layer "B.SilkS")
		)
		(fp_line
			(start -0.7874 0.4064)
			(end 0.7874 0.4064)
			(stroke
				(width 0.1524)
				(type default)
			)
			(layer "B.SilkS")
		)
		(fp_line
			(start 0.67945 -0.305054)
			(end 0.12065 -0.305054)
			(stroke
				(width 0.1)
				(type default)
			)
			(layer "B.Fab")
		)
		(fp_line
			(start 0.12065 -0.305054)
			(end 0.12065 -0.2794)
			(stroke
				(width 0.1)
				(type default)
			)
			(layer "B.Fab")
		)
		(fp_line
			(start -0.12065 -0.3048)
			(end -0.67945 -0.3048)
			(stroke
				(width 0.1)
				(type default)
			)
			(layer "B.Fab")
		)
		(fp_line
			(start -0.67945 -0.3048)
			(end -0.67945 0.3048)
			(stroke
				(width 0.1)
				(type default)
			)
			(layer "B.Fab")
		)
		(fp_line
			(start 0.12065 -0.2794)
			(end -0.12065 -0.2794)
			(stroke
				(width 0.1)
				(type default)
			)
			(layer "B.Fab")
		)
		(fp_line
			(start -0.12065 -0.2794)
			(end -0.12065 -0.3048)
			(stroke
				(width 0.1)
				(type default)
			)
			(layer "B.Fab")
		)
		(fp_line
			(start 0.12065 0.2794)
			(end 0.12065 0.3048)
			(stroke
				(width 0.1)
				(type default)
			)
			(layer "B.Fab")
		)
		(fp_line
			(start -0.120396 0.2794)
			(end 0.12065 0.2794)
			(stroke
				(width 0.1)
				(type default)
			)
			(layer "B.Fab")
		)
		(fp_line
			(start 0.67945 0.3048)
			(end 0.67945 -0.305054)
			(stroke
				(width 0.1)
				(type default)
			)
			(layer "B.Fab")
		)
		(fp_line
			(start 0.12065 0.3048)
			(end 0.67945 0.3048)
			(stroke
				(width 0.1)
				(type default)
			)
			(layer "B.Fab")
		)
		(fp_line
			(start -0.120396 0.3048)
			(end -0.120396 0.2794)
			(stroke
				(width 0.1)
				(type default)
			)
			(layer "B.Fab")
		)
		(fp_line
			(start -0.67945 0.3048)
			(end -0.120396 0.3048)
			(stroke
				(width 0.1)
				(type default)
			)
			(layer "B.Fab")
		)
		(pad "1" smd circle
			(at 0.40005 0 270)
			(size 0 0)
			(layers "B.Cu" "B.Mask" "B.Paste")
			(net "GND")
		)
		(pad "2" smd circle
			(at -0.40005 0 270)
			(size 0 0)
			(layers "B.Cu" "B.Mask" "B.Paste")
			(net "FAN_3_CLREF")
		)
	)
	(footprint ""
		(layer "B.Cu")
		(at 9.91997 -262.678672 90)
		(property "Reference" "PC64"
			(at 0 0 90)
			(layer "B.SilkS")
			(hide yes)
			(effects
				(font
					(size 1.27 1.27)
				)
				(justify mirror)
			)
		)
		(property "Value" ""
			(at 0 0 90)
			(layer "B.Fab")
			(effects
				(font
					(size 1.27 1.27)
				)
				(justify mirror)
			)
		)
		(duplicate_pad_numbers_are_jumpers no)
		(fp_line
			(start 1.524 -0.762)
			(end -1.524 -0.762)
			(stroke
				(width 0.1524)
				(type default)
			)
			(layer "B.SilkS")
		)
		(fp_line
			(start -1.524 -0.762)
			(end -1.524 0.762)
			(stroke
				(width 0.1524)
				(type default)
			)
			(layer "B.SilkS")
		)
		(fp_line
			(start 1.524 0.762)
			(end 1.524 -0.762)
			(stroke
				(width 0.1524)
				(type default)
			)
			(layer "B.SilkS")
		)
		(fp_line
			(start -1.524 0.762)
			(end 1.524 0.762)
			(stroke
				(width 0.1524)
				(type default)
			)
			(layer "B.SilkS")
		)
		(fp_line
			(start 1.1049 -0.724916)
			(end 1.1049 0.724916)
			(stroke
				(width 0.1)
				(type default)
			)
			(layer "B.Fab")
		)
		(fp_line
			(start -1.1049 -0.724916)
			(end 1.1049 -0.724916)
			(stroke
				(width 0.1)
				(type default)
			)
			(layer "B.Fab")
		)
		(fp_line
			(start 1.1049 0.724916)
			(end -1.1049 0.724916)
			(stroke
				(width 0.1)
				(type default)
			)
			(layer "B.Fab")
		)
		(fp_line
			(start -1.1049 0.724916)
			(end -1.1049 -0.724916)
			(stroke
				(width 0.1)
				(type default)
			)
			(layer "B.Fab")
		)
		(pad "1" smd rect
			(at 0.889 0 90)
			(size 1.016 1.27)
			(layers "B.Cu" "B.Mask" "B.Paste")
			(net "P52V_HSC")
		)
		(pad "2" smd rect
			(at -0.889 0 90)
			(size 1.016 1.27)
			(layers "B.Cu" "B.Mask" "B.Paste")
			(net "GND")
		)
	)
)
